FILE_TYPE = MACRO_DRAWING;
SET COLOR_WIRE YELLOW;
SET COLOR_PROP ORANGE;
SET COLOR_DOT WHITE;
SET COLOR_ARC YELLOW;
SET COLOR_BODY GREEN;
SET COLOR_NOTE PURPLE;
SET PROP_DISPLAY VALUE;
SET PAGE_NUMBER P81;
FORCEADD QUANTA_TITLE_BLOCK_C..1
(6425 -3550);
FORCEPROP 1 LAST CUSTOM_TXT_CDS <NAME_2>
J 0
(3250 -3500);
FORCEPROP 1 LAST CUSTOM_TXT_CDS <NAME_1>
J 0
(3250 -3375);
FORCEPROP 1 LAST CUSTOM_TXT_CDS <Q_NUMBER>
J 0
(5022 -3447);
DISPLAY 1.212766 (5022 -3447);
FORCEPROP 1 LAST CUSTOM_TXT_CDS <Q_PROJ>
J 0
(4043 -3448);
DISPLAY 1.212766 (4043 -3448);
FORCEPROP 1 LAST CUSTOM_TXT_CDS <Q_REV>
J 0
(6241 -3447);
DISPLAY 1.212766 (6241 -3447);
FORCEPROP 1 LAST CUSTOM_TXT_CDS <CON_LAST_MODIFIED>
J 0
(4540 -3535);
DISPLAY 0.978723 (4540 -3535);
FORCEPROP 1 LAST CUSTOM_TXT_CDS <CON_PAGE_NUM> OF <CON_TOTAL_PAGES>
J 0
(5979 -3532);
DISPLAY 0.978723 (5979 -3532);
FORCEPROP 1 LAST Q_TITLE BLANK
J 0
(-2941 -3524);
DISPLAY 2.446809 (-2941 -3524);
PAINT GREEN (-2941 -3524);
FORCEPROP 1 LAST Q_DEPT 
J 1
(2662 -3501);
DISPLAY 1.957447 (2662 -3501);
PAINT GREEN (2662 -3501);
FORCEPROP 2 LAST CDS_XR_PAGE_TITLE CR-81 : @S9S_MB_2U_LIB.S9S_MB_2U(SCH_1):PAGE81
J 0
(-1465 1700);
DISPLAY 0.638298 (-1465 1700);
PAINT PINK (-1465 1700);
DISPLAY INVISIBLE (-1465 1700);
FORCEPROP 2 LAST PAGE_BORDER TRUE
J 0
(-1465 1700);
DISPLAY 0.638298 (-1465 1700);
PAINT PINK (-1465 1700);
DISPLAY INVISIBLE (-1465 1700);
FORCEPROP 1 LAST COMMENT_BODY TRUE
J 0
(6437 -3563);
DISPLAY 0.978723 (6437 -3563);
PAINT GREEN (6437 -3563);
DISPLAY INVISIBLE (6437 -3563);
FORCEPROP 1 LAST CDS_LMAN_SYM_OUTLINE -9475,6775,100,-125
J 0
(6425 -3550);
DISPLAY 0.468085 (6425 -3550);
PAINT GREEN (6425 -3550);
DISPLAY INVISIBLE (6425 -3550);
FORCEPROP 2 LAST CDS_LIB pure_quanta
J 0
(6425 -3550);
DISPLAY INVISIBLE (6425 -3550);
FORCEPROP 2 LAST CUSTOM_TXT_CDS <XR_PAGE_TITLE>
J 0
(-1465 1700);
DISPLAY 0.638298 (-1465 1700);
PAINT PINK (-1465 1700);
DISPLAY INVISIBLE (-1465 1700);
FORCEPROP 0 LAST CDS_CON_LAST_MODIFIED Thu Aug 24 16:13:00 2023
J 0
(4540 -3535);
DISPLAY INVISIBLE (4540 -3535);
FORCENOTE
THIS PAGE WAS INTENTIONALLY LEFT BLANK
(-2675 -75) 0;
DISPLAY LEFT (-2675 -75);
DISPLAY 4.914894 (-2675 -75);
QUIT
